(kicad_pcb
	(version 20260206)
	(generator "pcbnew")
	(generator_version "10.0")
	(general
		(thickness 1.6)
		(legacy_teardrops no)
	)
	(paper "A4")
	(title_block
		(title "peb — Lightning_PEB_BRD.brd")
		(comment 1 "Lightning (Wiwynn / Facebook NVMe JBOF) / footprint 1445 of 2563 (U1), pads 469-584 of 1311")
	)
	(layers
		(0 "F.Cu" signal "TOP")
		(4 "In1.Cu" signal "L2GND")
		(6 "In2.Cu" signal "L3")
		(8 "In3.Cu" signal "L4VCC")
		(10 "In4.Cu" signal "L5VCC")
		(12 "In5.Cu" signal "L6")
		(14 "In6.Cu" signal "L7GND")
		(2 "B.Cu" signal "BOTTOM")
		(9 "F.Adhes" user "F.Adhesive")
		(11 "B.Adhes" user "B.Adhesive")
		(13 "F.Paste" user "Package Geometry/Pastemask Top")
		(15 "B.Paste" user "Package Geometry/Pastemask Bottom")
		(5 "F.SilkS" user "Ref Des/Silkscreen Top")
		(7 "B.SilkS" user "Ref Des/Silkscreen Bottom")
		(1 "F.Mask" user "Board Geometry/Soldermask Top")
		(3 "B.Mask" user "Board Geometry/Soldermask Bottom")
		(17 "Dwgs.User" user "User.Drawings")
		(19 "Cmts.User" user "User.Comments")
		(21 "Eco1.User" user "User.Eco1")
		(23 "Eco2.User" user "User.Eco2")
		(25 "Edge.Cuts" user "Board Geometry/Outline")
		(27 "Margin" user)
		(31 "F.CrtYd" user "Package Geometry/Place Bound Top")
		(29 "B.CrtYd" user "Package Geometry/Place Bound Bottom")
		(35 "F.Fab" user "Ref Des/Assembly Top")
		(33 "B.Fab" user "Ref Des/Assembly Bottom")
	)
	(footprint ""
		(layer "F.Cu")
		(at 240.599976 -47.999904 -90)
		(property "Reference" "U1"
			(at 0 0 270)
			(layer "F.SilkS")
			(hide yes)
			(effects
				(font
					(size 1.27 1.27)
				)
			)
		)
		(property "Value" "PM8546A-FEIP-GP"
			(at -25.785064 -6.40334 270)
			(unlocked yes)
			(layer "F.Fab")
			(hide yes)
			(effects
				(font
					(size 1.016 1.016)
					(thickness 0.1524)
				)
			)
		)
		(property "Device Type" "BGA1311C37D5H134"
			(at -25.785064 -7.92734 270)
			(unlocked yes)
			(layer "F.Fab")
			(hide yes)
			(effects
				(font
					(size 1.016 1.016)
					(thickness 0.1524)
				)
			)
		)
		(duplicate_pad_numbers_are_jumpers no)
		(pad "AN13" smd circle
			(at -5.999988 13.999972 270)
			(size 0.4572 0.4572)
			(layers "F.Cu" "F.Mask" "F.Paste")
			(net "PCIE_RX_P69")
		)
		(pad "AN14" smd circle
			(at -4.99999 13.999972 270)
			(size 0.4572 0.4572)
			(layers "F.Cu" "F.Mask" "F.Paste")
			(net "PCIE_RX_N70")
		)
		(pad "AN15" smd circle
			(at -3.999992 13.999972 270)
			(size 0.4572 0.4572)
			(layers "F.Cu" "F.Mask" "F.Paste")
			(net "PCIE_RX_P71")
		)
		(pad "AN16" smd circle
			(at -2.999994 13.999972 270)
			(size 0.4572 0.4572)
			(layers "F.Cu" "F.Mask" "F.Paste")
			(net "GND")
		)
		(pad "AN17" smd circle
			(at -1.999996 13.999972 270)
			(size 0.4572 0.4572)
			(layers "F.Cu" "F.Mask" "F.Paste")
			(net "PCIE_RX_N72")
		)
		(pad "AN18" smd circle
			(at -0.999998 13.999972 270)
			(size 0.4572 0.4572)
			(layers "F.Cu" "F.Mask" "F.Paste")
			(net "PCIE_RX_P73")
		)
		(pad "AN19" smd circle
			(at 0 13.999972 270)
			(size 0.4572 0.4572)
			(layers "F.Cu" "F.Mask" "F.Paste")
			(net "PCIE_RX_N74")
		)
		(pad "AN20" smd circle
			(at 0.999998 13.999972 270)
			(size 0.4572 0.4572)
			(layers "F.Cu" "F.Mask" "F.Paste")
			(net "PCIE_RX_P75")
		)
		(pad "AN21" smd circle
			(at 1.999996 13.999972 270)
			(size 0.4572 0.4572)
			(layers "F.Cu" "F.Mask" "F.Paste")
			(net "PCIE_RX_N76")
		)
		(pad "AN22" smd circle
			(at 2.999994 13.999972 270)
			(size 0.4572 0.4572)
			(layers "F.Cu" "F.Mask" "F.Paste")
			(net "Net_305")
		)
		(pad "AN23" smd circle
			(at 3.999992 13.999972 270)
			(size 0.4572 0.4572)
			(layers "F.Cu" "F.Mask" "F.Paste")
			(net "PCIE_RX_N78")
		)
		(pad "AN24" smd circle
			(at 4.99999 13.999972 270)
			(size 0.4572 0.4572)
			(layers "F.Cu" "F.Mask" "F.Paste")
			(net "Net_306")
		)
		(pad "AN25" smd circle
			(at 5.999988 13.999972 270)
			(size 0.4572 0.4572)
			(layers "F.Cu" "F.Mask" "F.Paste")
			(net "GND")
		)
		(pad "AN26" smd circle
			(at 6.999986 13.999972 270)
			(size 0.4572 0.4572)
			(layers "F.Cu" "F.Mask" "F.Paste")
			(net "PCIE_RX_N80")
		)
		(pad "AN27" smd circle
			(at 7.999984 13.999972 270)
			(size 0.4572 0.4572)
			(layers "F.Cu" "F.Mask" "F.Paste")
			(net "PCIE_RX_P81")
		)
		(pad "AN28" smd circle
			(at 8.999982 13.999972 270)
			(size 0.4572 0.4572)
			(layers "F.Cu" "F.Mask" "F.Paste")
			(net "PCIE_RX_N82")
		)
		(pad "AN29" smd circle
			(at 9.99998 13.999972 270)
			(size 0.4572 0.4572)
			(layers "F.Cu" "F.Mask" "F.Paste")
			(net "PCIE_RX_P83")
		)
		(pad "AN30" smd circle
			(at 10.999978 13.999972 270)
			(size 0.4572 0.4572)
			(layers "F.Cu" "F.Mask" "F.Paste")
			(net "PCIE_RX_N84")
		)
		(pad "AN31" smd circle
			(at 11.999976 13.999972 270)
			(size 0.4572 0.4572)
			(layers "F.Cu" "F.Mask" "F.Paste")
			(net "PCIE_RX_P85")
		)
		(pad "AN32" smd circle
			(at 12.999974 13.999972 270)
			(size 0.4572 0.4572)
			(layers "F.Cu" "F.Mask" "F.Paste")
			(net "PCIE_RX_N86")
		)
		(pad "AN33" smd circle
			(at 13.999972 13.999972 270)
			(size 0.4572 0.4572)
			(layers "F.Cu" "F.Mask" "F.Paste")
			(net "PCIE_RX_P87")
		)
		(pad "AN34" smd circle
			(at 14.99997 13.999972 270)
			(size 0.4572 0.4572)
			(layers "F.Cu" "F.Mask" "F.Paste")
			(net "GND")
		)
		(pad "AN35" smd circle
			(at 15.999968 13.999972 270)
			(size 0.4572 0.4572)
			(layers "F.Cu" "F.Mask" "F.Paste")
			(net "PCIE_TX_CAP_P92")
		)
		(pad "AN36" smd circle
			(at 16.999966 13.999972 270)
			(size 0.4572 0.4572)
			(layers "F.Cu" "F.Mask" "F.Paste")
			(net "PCIE_TX_CAP_N92")
		)
		(pad "AP1" smd circle
			(at -17.999964 14.99997 270)
			(size 0.4572 0.4572)
			(layers "F.Cu" "F.Mask" "F.Paste")
			(net "PCIE_TX_CAP_N61")
		)
		(pad "AP2" smd circle
			(at -16.999966 14.99997 270)
			(size 0.4572 0.4572)
			(layers "F.Cu" "F.Mask" "F.Paste")
			(net "PCIE_TX_CAP_P61")
		)
		(pad "AP3" smd circle
			(at -15.999968 14.99997 270)
			(size 0.4572 0.4572)
			(layers "F.Cu" "F.Mask" "F.Paste")
			(net "GND")
		)
		(pad "AP4" smd circle
			(at -14.99997 14.99997 270)
			(size 0.4572 0.4572)
			(layers "F.Cu" "F.Mask" "F.Paste")
			(net "PCIE_RX_N61")
		)
		(pad "AP5" smd circle
			(at -13.999972 14.99997 270)
			(size 0.4572 0.4572)
			(layers "F.Cu" "F.Mask" "F.Paste")
			(net "PCIE_RX_P61")
		)
		(pad "AP6" smd circle
			(at -12.999974 14.99997 270)
			(size 0.4572 0.4572)
			(layers "F.Cu" "F.Mask" "F.Paste")
			(net "GND")
		)
		(pad "AP7" smd circle
			(at -11.999976 14.99997 270)
			(size 0.4572 0.4572)
			(layers "F.Cu" "F.Mask" "F.Paste")
			(net "GND")
		)
		(pad "AP8" smd circle
			(at -10.999978 14.99997 270)
			(size 0.4572 0.4572)
			(layers "F.Cu" "F.Mask" "F.Paste")
			(net "GND")
		)
		(pad "AP9" smd circle
			(at -9.99998 14.99997 270)
			(size 0.4572 0.4572)
			(layers "F.Cu" "F.Mask" "F.Paste")
			(net "PCIE_RX_N65")
		)
		(pad "AP10" smd circle
			(at -8.999982 14.99997 270)
			(size 0.4572 0.4572)
			(layers "F.Cu" "F.Mask" "F.Paste")
			(net "GND")
		)
		(pad "AP11" smd circle
			(at -7.999984 14.99997 270)
			(size 0.4572 0.4572)
			(layers "F.Cu" "F.Mask" "F.Paste")
			(net "PCIE_RX_N67")
		)
		(pad "AP12" smd circle
			(at -6.999986 14.99997 270)
			(size 0.4572 0.4572)
			(layers "F.Cu" "F.Mask" "F.Paste")
			(net "GND")
		)
		(pad "AP13" smd circle
			(at -5.999988 14.99997 270)
			(size 0.4572 0.4572)
			(layers "F.Cu" "F.Mask" "F.Paste")
			(net "PCIE_RX_N69")
		)
		(pad "AP14" smd circle
			(at -4.99999 14.99997 270)
			(size 0.4572 0.4572)
			(layers "F.Cu" "F.Mask" "F.Paste")
			(net "GND")
		)
		(pad "AP15" smd circle
			(at -3.999992 14.99997 270)
			(size 0.4572 0.4572)
			(layers "F.Cu" "F.Mask" "F.Paste")
			(net "PCIE_RX_N71")
		)
		(pad "AP16" smd circle
			(at -2.999994 14.99997 270)
			(size 0.4572 0.4572)
			(layers "F.Cu" "F.Mask" "F.Paste")
			(net "GND")
		)
		(pad "AP17" smd circle
			(at -1.999996 14.99997 270)
			(size 0.4572 0.4572)
			(layers "F.Cu" "F.Mask" "F.Paste")
			(net "GND")
		)
		(pad "AP18" smd circle
			(at -0.999998 14.99997 270)
			(size 0.4572 0.4572)
			(layers "F.Cu" "F.Mask" "F.Paste")
			(net "PCIE_RX_N73")
		)
		(pad "AP19" smd circle
			(at 0 14.99997 270)
			(size 0.4572 0.4572)
			(layers "F.Cu" "F.Mask" "F.Paste")
			(net "GND")
		)
		(pad "AP20" smd circle
			(at 0.999998 14.99997 270)
			(size 0.4572 0.4572)
			(layers "F.Cu" "F.Mask" "F.Paste")
			(net "PCIE_RX_N75")
		)
		(pad "AP21" smd circle
			(at 1.999996 14.99997 270)
			(size 0.4572 0.4572)
			(layers "F.Cu" "F.Mask" "F.Paste")
			(net "GND")
		)
		(pad "AP22" smd circle
			(at 2.999994 14.99997 270)
			(size 0.4572 0.4572)
			(layers "F.Cu" "F.Mask" "F.Paste")
			(net "Net_303")
		)
		(pad "AP23" smd circle
			(at 3.999992 14.99997 270)
			(size 0.4572 0.4572)
			(layers "F.Cu" "F.Mask" "F.Paste")
			(net "GND")
		)
		(pad "AP24" smd circle
			(at 4.99999 14.99997 270)
			(size 0.4572 0.4572)
			(layers "F.Cu" "F.Mask" "F.Paste")
			(net "Net_304")
		)
		(pad "AP25" smd circle
			(at 5.999988 14.99997 270)
			(size 0.4572 0.4572)
			(layers "F.Cu" "F.Mask" "F.Paste")
			(net "GND")
		)
		(pad "AP26" smd circle
			(at 6.999986 14.99997 270)
			(size 0.4572 0.4572)
			(layers "F.Cu" "F.Mask" "F.Paste")
			(net "GND")
		)
		(pad "AP27" smd circle
			(at 7.999984 14.99997 270)
			(size 0.4572 0.4572)
			(layers "F.Cu" "F.Mask" "F.Paste")
			(net "PCIE_RX_N81")
		)
		(pad "AP28" smd circle
			(at 8.999982 14.99997 270)
			(size 0.4572 0.4572)
			(layers "F.Cu" "F.Mask" "F.Paste")
			(net "GND")
		)
		(pad "AP29" smd circle
			(at 9.99998 14.99997 270)
			(size 0.4572 0.4572)
			(layers "F.Cu" "F.Mask" "F.Paste")
			(net "PCIE_RX_N83")
		)
		(pad "AP30" smd circle
			(at 10.999978 14.99997 270)
			(size 0.4572 0.4572)
			(layers "F.Cu" "F.Mask" "F.Paste")
			(net "GND")
		)
		(pad "AP31" smd circle
			(at 11.999976 14.99997 270)
			(size 0.4572 0.4572)
			(layers "F.Cu" "F.Mask" "F.Paste")
			(net "PCIE_RX_N85")
		)
		(pad "AP32" smd circle
			(at 12.999974 14.99997 270)
			(size 0.4572 0.4572)
			(layers "F.Cu" "F.Mask" "F.Paste")
			(net "GND")
		)
		(pad "AP33" smd circle
			(at 13.999972 14.99997 270)
			(size 0.4572 0.4572)
			(layers "F.Cu" "F.Mask" "F.Paste")
			(net "PCIE_RX_N87")
		)
		(pad "AP34" smd circle
			(at 14.99997 14.99997 270)
			(size 0.4572 0.4572)
			(layers "F.Cu" "F.Mask" "F.Paste")
			(net "GND")
		)
		(pad "AP35" smd circle
			(at 15.999968 14.99997 270)
			(size 0.4572 0.4572)
			(layers "F.Cu" "F.Mask" "F.Paste")
			(net "GND")
		)
		(pad "AP36" smd circle
			(at 16.999966 14.99997 270)
			(size 0.4572 0.4572)
			(layers "F.Cu" "F.Mask" "F.Paste")
			(net "PCIE_TX_CAP_P91")
		)
		(pad "AP37" smd circle
			(at 17.999964 14.99997 270)
			(size 0.4572 0.4572)
			(layers "F.Cu" "F.Mask" "F.Paste")
			(net "PCIE_TX_CAP_N91")
		)
		(pad "AR2" smd circle
			(at -16.999966 15.999968 270)
			(size 0.508 0.508)
			(layers "F.Cu" "F.Mask" "F.Paste")
			(net "PCIE_TX_CAP_N62")
		)
		(pad "AR3" smd circle
			(at -15.999968 15.999968 270)
			(size 0.508 0.508)
			(layers "F.Cu" "F.Mask" "F.Paste")
			(net "PCIE_TX_CAP_P62")
		)
		(pad "AR4" smd circle
			(at -14.99997 15.999968 270)
			(size 0.4572 0.4572)
			(layers "F.Cu" "F.Mask" "F.Paste")
			(net "GND")
		)
		(pad "AR5" smd circle
			(at -13.999972 15.999968 270)
			(size 0.4572 0.4572)
			(layers "F.Cu" "F.Mask" "F.Paste")
			(net "PCIE_RX_N62")
		)
		(pad "AR6" smd circle
			(at -12.999974 15.999968 270)
			(size 0.4572 0.4572)
			(layers "F.Cu" "F.Mask" "F.Paste")
			(net "PCIE_RX_P62")
		)
		(pad "AR7" smd circle
			(at -11.999976 15.999968 270)
			(size 0.4572 0.4572)
			(layers "F.Cu" "F.Mask" "F.Paste")
			(net "GND")
		)
		(pad "AR8" smd circle
			(at -10.999978 15.999968 270)
			(size 0.4572 0.4572)
			(layers "F.Cu" "F.Mask" "F.Paste")
			(net "PCIE_TX_CAP_P64")
		)
		(pad "AR9" smd circle
			(at -9.99998 15.999968 270)
			(size 0.4572 0.4572)
			(layers "F.Cu" "F.Mask" "F.Paste")
			(net "GND")
		)
		(pad "AR10" smd circle
			(at -8.999982 15.999968 270)
			(size 0.4572 0.4572)
			(layers "F.Cu" "F.Mask" "F.Paste")
			(net "PCIE_TX_CAP_P66")
		)
		(pad "AR11" smd circle
			(at -7.999984 15.999968 270)
			(size 0.4572 0.4572)
			(layers "F.Cu" "F.Mask" "F.Paste")
			(net "GND")
		)
		(pad "AR12" smd circle
			(at -6.999986 15.999968 270)
			(size 0.4572 0.4572)
			(layers "F.Cu" "F.Mask" "F.Paste")
			(net "PCIE_TX_CAP_P68")
		)
		(pad "AR13" smd circle
			(at -5.999988 15.999968 270)
			(size 0.4572 0.4572)
			(layers "F.Cu" "F.Mask" "F.Paste")
			(net "GND")
		)
		(pad "AR14" smd circle
			(at -4.99999 15.999968 270)
			(size 0.4572 0.4572)
			(layers "F.Cu" "F.Mask" "F.Paste")
			(net "PCIE_TX_CAP_P70")
		)
		(pad "AR15" smd circle
			(at -3.999992 15.999968 270)
			(size 0.4572 0.4572)
			(layers "F.Cu" "F.Mask" "F.Paste")
			(net "GND")
		)
		(pad "AR16" smd circle
			(at -2.999994 15.999968 270)
			(size 0.4572 0.4572)
			(layers "F.Cu" "F.Mask" "F.Paste")
			(net "GND")
		)
		(pad "AR17" smd circle
			(at -1.999996 15.999968 270)
			(size 0.4572 0.4572)
			(layers "F.Cu" "F.Mask" "F.Paste")
			(net "PCIE_TX_CAP_P72")
		)
		(pad "AR18" smd circle
			(at -0.999998 15.999968 270)
			(size 0.4572 0.4572)
			(layers "F.Cu" "F.Mask" "F.Paste")
			(net "GND")
		)
		(pad "AR19" smd circle
			(at 0 15.999968 270)
			(size 0.4572 0.4572)
			(layers "F.Cu" "F.Mask" "F.Paste")
			(net "PCIE_TX_CAP_P74")
		)
		(pad "AR20" smd circle
			(at 0.999998 15.999968 270)
			(size 0.4572 0.4572)
			(layers "F.Cu" "F.Mask" "F.Paste")
			(net "GND")
		)
		(pad "AR21" smd circle
			(at 1.999996 15.999968 270)
			(size 0.4572 0.4572)
			(layers "F.Cu" "F.Mask" "F.Paste")
			(net "PCIE_TX_CAP_P76")
		)
		(pad "AR22" smd circle
			(at 2.999994 15.999968 270)
			(size 0.4572 0.4572)
			(layers "F.Cu" "F.Mask" "F.Paste")
			(net "GND")
		)
		(pad "AR23" smd circle
			(at 3.999992 15.999968 270)
			(size 0.4572 0.4572)
			(layers "F.Cu" "F.Mask" "F.Paste")
			(net "PCIE_TX_CAP_P78")
		)
		(pad "AR24" smd circle
			(at 4.99999 15.999968 270)
			(size 0.4572 0.4572)
			(layers "F.Cu" "F.Mask" "F.Paste")
			(net "GND")
		)
		(pad "AR25" smd circle
			(at 5.999988 15.999968 270)
			(size 0.4572 0.4572)
			(layers "F.Cu" "F.Mask" "F.Paste")
			(net "GND")
		)
		(pad "AR26" smd circle
			(at 6.999986 15.999968 270)
			(size 0.4572 0.4572)
			(layers "F.Cu" "F.Mask" "F.Paste")
			(net "PCIE_TX_CAP_P80")
		)
		(pad "AR27" smd circle
			(at 7.999984 15.999968 270)
			(size 0.4572 0.4572)
			(layers "F.Cu" "F.Mask" "F.Paste")
			(net "GND")
		)
		(pad "AR28" smd circle
			(at 8.999982 15.999968 270)
			(size 0.4572 0.4572)
			(layers "F.Cu" "F.Mask" "F.Paste")
			(net "PCIE_TX_CAP_P82")
		)
		(pad "AR29" smd circle
			(at 9.99998 15.999968 270)
			(size 0.4572 0.4572)
			(layers "F.Cu" "F.Mask" "F.Paste")
			(net "GND")
		)
		(pad "AR30" smd circle
			(at 10.999978 15.999968 270)
			(size 0.4572 0.4572)
			(layers "F.Cu" "F.Mask" "F.Paste")
			(net "PCIE_TX_CAP_P84")
		)
		(pad "AR31" smd circle
			(at 11.999976 15.999968 270)
			(size 0.4572 0.4572)
			(layers "F.Cu" "F.Mask" "F.Paste")
			(net "GND")
		)
		(pad "AR32" smd circle
			(at 12.999974 15.999968 270)
			(size 0.4572 0.4572)
			(layers "F.Cu" "F.Mask" "F.Paste")
			(net "PCIE_TX_CAP_P86")
		)
		(pad "AR33" smd circle
			(at 13.999972 15.999968 270)
			(size 0.4572 0.4572)
			(layers "F.Cu" "F.Mask" "F.Paste")
			(net "GND")
		)
		(pad "AR34" smd circle
			(at 14.99997 15.999968 270)
			(size 0.4572 0.4572)
			(layers "F.Cu" "F.Mask" "F.Paste")
			(net "GND")
		)
		(pad "AR35" smd circle
			(at 15.999968 15.999968 270)
			(size 0.508 0.508)
			(layers "F.Cu" "F.Mask" "F.Paste")
			(net "PCIE_TX_CAP_P90")
		)
		(pad "AR36" smd circle
			(at 16.999966 15.999968 270)
			(size 0.508 0.508)
			(layers "F.Cu" "F.Mask" "F.Paste")
			(net "PCIE_TX_CAP_N90")
		)
		(pad "AT1" smd circle
			(at -17.999964 16.999966 270)
			(size 0.508 0.508)
			(layers "F.Cu" "F.Mask" "F.Paste")
			(net "PCIE_TX_CAP_N63")
		)
		(pad "AT2" smd circle
			(at -16.999966 16.999966 270)
			(size 0.508 0.508)
			(layers "F.Cu" "F.Mask" "F.Paste")
			(net "PCIE_TX_CAP_P63")
		)
		(pad "AT3" smd circle
			(at -15.999968 16.999966 270)
			(size 0.508 0.508)
			(layers "F.Cu" "F.Mask" "F.Paste")
			(net "GND")
		)
		(pad "AT4" smd circle
			(at -14.99997 16.999966 270)
			(size 0.4572 0.4572)
			(layers "F.Cu" "F.Mask" "F.Paste")
			(net "PCIE_RX_N63")
		)
		(pad "AT5" smd circle
			(at -13.999972 16.999966 270)
			(size 0.4572 0.4572)
			(layers "F.Cu" "F.Mask" "F.Paste")
			(net "PCIE_RX_P63")
		)
		(pad "AT6" smd circle
			(at -12.999974 16.999966 270)
			(size 0.4572 0.4572)
			(layers "F.Cu" "F.Mask" "F.Paste")
			(net "GND")
		)
		(pad "AT7" smd circle
			(at -11.999976 16.999966 270)
			(size 0.4572 0.4572)
			(layers "F.Cu" "F.Mask" "F.Paste")
			(net "GND")
		)
		(pad "AT8" smd circle
			(at -10.999978 16.999966 270)
			(size 0.4572 0.4572)
			(layers "F.Cu" "F.Mask" "F.Paste")
			(net "PCIE_TX_CAP_N64")
		)
		(pad "AT9" smd circle
			(at -9.99998 16.999966 270)
			(size 0.4572 0.4572)
			(layers "F.Cu" "F.Mask" "F.Paste")
			(net "PCIE_TX_CAP_P65")
		)
		(pad "AT10" smd circle
			(at -8.999982 16.999966 270)
			(size 0.4572 0.4572)
			(layers "F.Cu" "F.Mask" "F.Paste")
			(net "PCIE_TX_CAP_N66")
		)
		(pad "AT11" smd circle
			(at -7.999984 16.999966 270)
			(size 0.4572 0.4572)
			(layers "F.Cu" "F.Mask" "F.Paste")
			(net "PCIE_TX_CAP_P67")
		)
		(pad "AT12" smd circle
			(at -6.999986 16.999966 270)
			(size 0.4572 0.4572)
			(layers "F.Cu" "F.Mask" "F.Paste")
			(net "PCIE_TX_CAP_N68")
		)
		(pad "AT13" smd circle
			(at -5.999988 16.999966 270)
			(size 0.4572 0.4572)
			(layers "F.Cu" "F.Mask" "F.Paste")
			(net "PCIE_TX_CAP_P69")
		)
		(pad "AT14" smd circle
			(at -4.99999 16.999966 270)
			(size 0.4572 0.4572)
			(layers "F.Cu" "F.Mask" "F.Paste")
			(net "PCIE_TX_CAP_N70")
		)
		(pad "AT15" smd circle
			(at -3.999992 16.999966 270)
			(size 0.4572 0.4572)
			(layers "F.Cu" "F.Mask" "F.Paste")
			(net "PCIE_TX_CAP_P71")
		)
		(pad "AT16" smd circle
			(at -2.999994 16.999966 270)
			(size 0.4572 0.4572)
			(layers "F.Cu" "F.Mask" "F.Paste")
			(net "GND")
		)
		(pad "AT17" smd circle
			(at -1.999996 16.999966 270)
			(size 0.4572 0.4572)
			(layers "F.Cu" "F.Mask" "F.Paste")
			(net "PCIE_TX_CAP_N72")
		)
		(pad "AT18" smd circle
			(at -0.999998 16.999966 270)
			(size 0.4572 0.4572)
			(layers "F.Cu" "F.Mask" "F.Paste")
			(net "PCIE_TX_CAP_P73")
		)
		(pad "AT19" smd circle
			(at 0 16.999966 270)
			(size 0.4572 0.4572)
			(layers "F.Cu" "F.Mask" "F.Paste")
			(net "PCIE_TX_CAP_N74")
		)
		(pad "AT20" smd circle
			(at 0.999998 16.999966 270)
			(size 0.4572 0.4572)
			(layers "F.Cu" "F.Mask" "F.Paste")
			(net "PCIE_TX_CAP_P75")
		)
	)
)
